# S9S_MB_2U (Grand Teton) — schematic netlist excerpt (pin names and nets, part order shuffled) for the footprints in the layout excerpt that follows; sources: Cadence DE-HDL packaged netlist, KiCad conversion of 03242023_DA0F0TMBIJ0_F0T_Motherboard_J_brd_V01_OCP.brd

R3347  Q_RES  1 1% CHIP  pkg 0603LF  page 217 : A = P3V3_AUX ; B = P3V3_AUX_FPGA_VCCIO2

(kicad_pcb
	(version 20260206)
	(generator "pcbnew")
	(generator_version "10.0")
	(general
		(thickness 1.6)
		(legacy_teardrops no)
	)
	(paper "A4")
	(title_block
		(title "03242023_DA0F0TMBIJ0_F0T_Motherboard_J_brd_V01_OCP.brd")
		(comment 1 "Grand Teton / footprints 6105-6105 of 6105")
	)
	(layers
		(0 "F.Cu" signal "TOP")
		(4 "In1.Cu" signal "GND")
		(6 "In2.Cu" signal "IN1")
		(8 "In3.Cu" signal "GND1")
		(10 "In4.Cu" signal "IN2")
		(12 "In5.Cu" signal "GND2")
		(14 "In6.Cu" signal "IN3")
		(16 "In7.Cu" signal "GND3")
		(18 "In8.Cu" signal "VCC")
		(20 "In9.Cu" signal "VCC1")
		(22 "In10.Cu" signal "GND4")
		(24 "In11.Cu" signal "IN4")
		(26 "In12.Cu" signal "GND5")
		(28 "In13.Cu" signal "IN5")
		(30 "In14.Cu" signal "GND6")
		(32 "In15.Cu" signal "IN6")
		(34 "In16.Cu" signal "GND7")
		(2 "B.Cu" signal "BOTTOM")
		(9 "F.Adhes" user "F.Adhesive")
		(11 "B.Adhes" user "B.Adhesive")
		(13 "F.Paste" user "Package Geometry/Pastemask Top")
		(15 "B.Paste" user "Package Geometry/Pastemask Bottom")
		(5 "F.SilkS" user "Ref Des/Silkscreen Top")
		(7 "B.SilkS" user "Ref Des/Silkscreen Bottom")
		(1 "F.Mask" user "Board Geometry/Soldermask Top")
		(3 "B.Mask" user "Board Geometry/Soldermask Bottom")
		(17 "Dwgs.User" user "User.Drawings")
		(19 "Cmts.User" user "User.Comments")
		(21 "Eco1.User" user "User.Eco1")
		(23 "Eco2.User" user "User.Eco2")
		(25 "Edge.Cuts" user "Board Geometry/Outline")
		(27 "Margin" user)
		(31 "F.CrtYd" user "Package Geometry/Place Bound Top")
		(29 "B.CrtYd" user "Package Geometry/Place Bound Bottom")
		(35 "F.Fab" user "Ref Des/Assembly Top")
		(33 "B.Fab" user "Ref Des/Assembly Bottom")
	)
	(footprint ""
		(layer "B.Cu")
		(at 187.88888 -101.564948)
		(property "Reference" "R3347"
			(at 0 0 0)
			(layer "B.SilkS")
			(hide yes)
			(effects
				(font
					(size 1.27 1.27)
				)
				(justify mirror)
			)
		)
		(property "Value" ""
			(at 0 0 0)
			(layer "B.Fab")
			(effects
				(font
					(size 1.27 1.27)
				)
				(justify mirror)
			)
		)
		(duplicate_pad_numbers_are_jumpers no)
		(fp_line
			(start -1.2954 -0.5842)
			(end -1.2954 0.5842)
			(stroke
				(width 0.1524)
				(type default)
			)
			(layer "B.SilkS")
		)
		(fp_line
			(start -1.2954 0.5842)
			(end 1.2954 0.5842)
			(stroke
				(width 0.1524)
				(type default)
			)
			(layer "B.SilkS")
		)
		(fp_line
			(start 1.2954 -0.5842)
			(end -1.2954 -0.5842)
			(stroke
				(width 0.1524)
				(type default)
			)
			(layer "B.SilkS")
		)
		(fp_line
			(start 1.2954 0.5842)
			(end 1.2954 -0.5842)
			(stroke
				(width 0.1524)
				(type default)
			)
			(layer "B.SilkS")
		)
		(fp_line
			(start -1.1938 -0.406654)
			(end -1.1938 0.4064)
			(stroke
				(width 0.1)
				(type default)
			)
			(layer "B.Fab")
		)
		(fp_line
			(start -1.1938 0.4064)
			(end -0.8636 0.4064)
			(stroke
				(width 0.1)
				(type default)
			)
			(layer "B.Fab")
		)
		(fp_line
			(start -0.8636 -0.4572)
			(end -0.8636 -0.406654)
			(stroke
				(width 0.1)
				(type default)
			)
			(layer "B.Fab")
		)
		(fp_line
			(start -0.8636 -0.406654)
			(end -1.1938 -0.406654)
			(stroke
				(width 0.1)
				(type default)
			)
			(layer "B.Fab")
		)
		(fp_line
			(start -0.8636 0.4064)
			(end -0.8636 0.4572)
			(stroke
				(width 0.1)
				(type default)
			)
			(layer "B.Fab")
		)
		(fp_line
			(start -0.8636 0.4572)
			(end 0.8636 0.4572)
			(stroke
				(width 0.1)
				(type default)
			)
			(layer "B.Fab")
		)
		(fp_line
			(start 0.8636 -0.4572)
			(end -0.8636 -0.4572)
			(stroke
				(width 0.1)
				(type default)
			)
			(layer "B.Fab")
		)
		(fp_line
			(start 0.8636 -0.406654)
			(end 0.8636 -0.4572)
			(stroke
				(width 0.1)
				(type default)
			)
			(layer "B.Fab")
		)
		(fp_line
			(start 0.8636 0.4064)
			(end 1.1938 0.4064)
			(stroke
				(width 0.1)
				(type default)
			)
			(layer "B.Fab")
		)
		(fp_line
			(start 0.8636 0.4318)
			(end 0.8636 0.4064)
			(stroke
				(width 0.1)
				(type default)
			)
			(layer "B.Fab")
		)
		(fp_line
			(start 0.8636 0.4572)
			(end 0.8636 0.4318)
			(stroke
				(width 0.1)
				(type default)
			)
			(layer "B.Fab")
		)
		(fp_line
			(start 1.1938 -0.406654)
			(end 0.8636 -0.406654)
			(stroke
				(width 0.1)
				(type default)
			)
			(layer "B.Fab")
		)
		(fp_line
			(start 1.1938 0.4064)
			(end 1.1938 -0.406654)
			(stroke
				(width 0.1)
				(type default)
			)
			(layer "B.Fab")
		)
		(pad "1" smd rect
			(at 0.7366 0 270)
			(size 0.7112 0.8128)
			(layers "B.Cu" "B.Mask" "B.Paste")
			(net "P3V3_AUX")
		)
		(pad "2" smd rect
			(at -0.7366 0 270)
			(size 0.7112 0.8128)
			(layers "B.Cu" "B.Mask" "B.Paste")
			(net "P3V3_AUX_FPGA_VCCIO2")
		)
	)
)
